# T6G (Grand Teton) — schematic netlist excerpt (pin names and nets, part order shuffled) for the footprints in the layout excerpt that follows; sources: Cadence DE-HDL packaged netlist, KiCad conversion of 04192023_DAF0TMB3IC0_F0TG_MB_C_brd_V02_OCP.brd

R6708  Q_RES  0 5% CHIP  pkg 0201LF  page 320 : A = RST_RT_CPU1_P0_PERST_N ; B = RST_RT_CPU1_P0_PERST_R_N
PR135  Q_RES  5.6 1% CHIP  pkg 0402LF  page 208 : A = SW_PVDD11_S3_P0_BOOT1 ; B = SW_PVDD11_S3_P0_BOOT1_RC
R2990  Q_RES  33.2 1% CHIP  pkg 0402LF  page 248 : A = SMB_2_BMC_GPU_BUF_R_SCL ; B = SMB_2_BMC_GPU_BUF_SCL

(kicad_pcb
	(version 20260206)
	(generator "pcbnew")
	(generator_version "10.0")
	(general
		(thickness 1.6)
		(legacy_teardrops no)
	)
	(paper "A4")
	(title_block
		(title "04192023_DAF0TMB3IC0_F0TG_MB_C_brd_V02_OCP.brd")
		(comment 1 "Grand Teton / footprints 154-156 of 8354")
	)
	(layers
		(0 "F.Cu" signal "TOP")
		(4 "In1.Cu" signal "GND")
		(6 "In2.Cu" signal "IN1")
		(8 "In3.Cu" signal "GND1")
		(10 "In4.Cu" signal "IN2")
		(12 "In5.Cu" signal "GND2")
		(14 "In6.Cu" signal "IN3")
		(16 "In7.Cu" signal "GND3")
		(18 "In8.Cu" signal "VCC")
		(20 "In9.Cu" signal "VCC1")
		(22 "In10.Cu" signal "GND4")
		(24 "In11.Cu" signal "IN4")
		(26 "In12.Cu" signal "GND5")
		(28 "In13.Cu" signal "IN5")
		(30 "In14.Cu" signal "GND6")
		(32 "In15.Cu" signal "IN6")
		(34 "In16.Cu" signal "GND7")
		(2 "B.Cu" signal "BOTTOM")
		(9 "F.Adhes" user "F.Adhesive")
		(11 "B.Adhes" user "B.Adhesive")
		(13 "F.Paste" user "Package Geometry/Pastemask Top")
		(15 "B.Paste" user "Package Geometry/Pastemask Bottom")
		(5 "F.SilkS" user "Ref Des/Silkscreen Top")
		(7 "B.SilkS" user "Ref Des/Silkscreen Bottom")
		(1 "F.Mask" user "Board Geometry/Soldermask Top")
		(3 "B.Mask" user "Board Geometry/Soldermask Bottom")
		(17 "Dwgs.User" user "User.Drawings")
		(19 "Cmts.User" user "User.Comments")
		(21 "Eco1.User" user "User.Eco1")
		(23 "Eco2.User" user "User.Eco2")
		(25 "Edge.Cuts" user "Board Geometry/Outline")
		(27 "Margin" user)
		(31 "F.CrtYd" user "Package Geometry/Place Bound Top")
		(29 "B.CrtYd" user "Package Geometry/Place Bound Bottom")
		(35 "F.Fab" user "Ref Des/Assembly Top")
		(33 "B.Fab" user "Ref Des/Assembly Bottom")
	)
	(footprint ""
		(layer "F.Cu")
		(at 424.403266 -355.718364 90)
		(property "Reference" "PR135"
			(at 0 0 90)
			(layer "F.SilkS")
			(hide yes)
			(effects
				(font
					(size 1.27 1.27)
				)
			)
		)
		(property "Value" ""
			(at 0 0 90)
			(layer "F.Fab")
			(effects
				(font
					(size 1.27 1.27)
				)
			)
		)
		(duplicate_pad_numbers_are_jumpers no)
		(fp_line
			(start 0.7874 -0.4064)
			(end 0.7874 0.4064)
			(stroke
				(width 0.1524)
				(type default)
			)
			(layer "F.SilkS")
		)
		(fp_line
			(start -0.7874 -0.4064)
			(end 0.7874 -0.4064)
			(stroke
				(width 0.1524)
				(type default)
			)
			(layer "F.SilkS")
		)
		(fp_line
			(start 0.7874 0.4064)
			(end -0.7874 0.4064)
			(stroke
				(width 0.1524)
				(type default)
			)
			(layer "F.SilkS")
		)
		(fp_line
			(start -0.7874 0.4064)
			(end -0.7874 -0.4064)
			(stroke
				(width 0.1524)
				(type default)
			)
			(layer "F.SilkS")
		)
		(fp_line
			(start -0.12065 -0.305054)
			(end -0.12065 -0.2794)
			(stroke
				(width 0.1)
				(type default)
			)
			(layer "F.Fab")
		)
		(fp_line
			(start -0.67945 -0.305054)
			(end -0.12065 -0.305054)
			(stroke
				(width 0.1)
				(type default)
			)
			(layer "F.Fab")
		)
		(fp_line
			(start 0.67945 -0.3048)
			(end 0.67945 0.3048)
			(stroke
				(width 0.1)
				(type default)
			)
			(layer "F.Fab")
		)
		(fp_line
			(start 0.12065 -0.3048)
			(end 0.67945 -0.3048)
			(stroke
				(width 0.1)
				(type default)
			)
			(layer "F.Fab")
		)
		(fp_line
			(start 0.12065 -0.2794)
			(end 0.12065 -0.3048)
			(stroke
				(width 0.1)
				(type default)
			)
			(layer "F.Fab")
		)
		(fp_line
			(start -0.12065 -0.2794)
			(end 0.12065 -0.2794)
			(stroke
				(width 0.1)
				(type default)
			)
			(layer "F.Fab")
		)
		(fp_line
			(start 0.120396 0.2794)
			(end -0.12065 0.2794)
			(stroke
				(width 0.1)
				(type default)
			)
			(layer "F.Fab")
		)
		(fp_line
			(start -0.12065 0.2794)
			(end -0.12065 0.3048)
			(stroke
				(width 0.1)
				(type default)
			)
			(layer "F.Fab")
		)
		(fp_line
			(start 0.67945 0.3048)
			(end 0.120396 0.3048)
			(stroke
				(width 0.1)
				(type default)
			)
			(layer "F.Fab")
		)
		(fp_line
			(start 0.120396 0.3048)
			(end 0.120396 0.2794)
			(stroke
				(width 0.1)
				(type default)
			)
			(layer "F.Fab")
		)
		(fp_line
			(start -0.12065 0.3048)
			(end -0.67945 0.3048)
			(stroke
				(width 0.1)
				(type default)
			)
			(layer "F.Fab")
		)
		(fp_line
			(start -0.67945 0.3048)
			(end -0.67945 -0.305054)
			(stroke
				(width 0.1)
				(type default)
			)
			(layer "F.Fab")
		)
		(pad "1" smd circle
			(at -0.40005 0 90)
			(size 0 0)
			(layers "F.Cu" "F.Mask" "F.Paste")
			(net "SW_PVDD11_S3_P0_BOOT1")
		)
		(pad "2" smd circle
			(at 0.40005 0 90)
			(size 0 0)
			(layers "F.Cu" "F.Mask" "F.Paste")
			(net "SW_PVDD11_S3_P0_BOOT1_RC")
		)
	)
	(footprint ""
		(layer "F.Cu")
		(at 35.881818 -436.433214)
		(property "Reference" "R2990"
			(at 0 0 0)
			(layer "F.SilkS")
			(hide yes)
			(effects
				(font
					(size 1.27 1.27)
				)
			)
		)
		(property "Value" ""
			(at 0 0 0)
			(layer "F.Fab")
			(effects
				(font
					(size 1.27 1.27)
				)
			)
		)
		(duplicate_pad_numbers_are_jumpers no)
		(fp_line
			(start -0.7874 -0.4064)
			(end 0.7874 -0.4064)
			(stroke
				(width 0.1524)
				(type default)
			)
			(layer "F.SilkS")
		)
		(fp_line
			(start -0.7874 0.4064)
			(end -0.7874 -0.4064)
			(stroke
				(width 0.1524)
				(type default)
			)
			(layer "F.SilkS")
		)
		(fp_line
			(start 0.7874 -0.4064)
			(end 0.7874 0.4064)
			(stroke
				(width 0.1524)
				(type default)
			)
			(layer "F.SilkS")
		)
		(fp_line
			(start 0.7874 0.4064)
			(end -0.7874 0.4064)
			(stroke
				(width 0.1524)
				(type default)
			)
			(layer "F.SilkS")
		)
		(fp_line
			(start -0.67945 -0.305054)
			(end -0.12065 -0.305054)
			(stroke
				(width 0.1)
				(type default)
			)
			(layer "F.Fab")
		)
		(fp_line
			(start -0.67945 0.3048)
			(end -0.67945 -0.305054)
			(stroke
				(width 0.1)
				(type default)
			)
			(layer "F.Fab")
		)
		(fp_line
			(start -0.12065 -0.305054)
			(end -0.12065 -0.2794)
			(stroke
				(width 0.1)
				(type default)
			)
			(layer "F.Fab")
		)
		(fp_line
			(start -0.12065 -0.2794)
			(end 0.12065 -0.2794)
			(stroke
				(width 0.1)
				(type default)
			)
			(layer "F.Fab")
		)
		(fp_line
			(start -0.12065 0.2794)
			(end -0.12065 0.3048)
			(stroke
				(width 0.1)
				(type default)
			)
			(layer "F.Fab")
		)
		(fp_line
			(start -0.12065 0.3048)
			(end -0.67945 0.3048)
			(stroke
				(width 0.1)
				(type default)
			)
			(layer "F.Fab")
		)
		(fp_line
			(start 0.120396 0.2794)
			(end -0.12065 0.2794)
			(stroke
				(width 0.1)
				(type default)
			)
			(layer "F.Fab")
		)
		(fp_line
			(start 0.120396 0.3048)
			(end 0.120396 0.2794)
			(stroke
				(width 0.1)
				(type default)
			)
			(layer "F.Fab")
		)
		(fp_line
			(start 0.12065 -0.3048)
			(end 0.67945 -0.3048)
			(stroke
				(width 0.1)
				(type default)
			)
			(layer "F.Fab")
		)
		(fp_line
			(start 0.12065 -0.2794)
			(end 0.12065 -0.3048)
			(stroke
				(width 0.1)
				(type default)
			)
			(layer "F.Fab")
		)
		(fp_line
			(start 0.67945 -0.3048)
			(end 0.67945 0.3048)
			(stroke
				(width 0.1)
				(type default)
			)
			(layer "F.Fab")
		)
		(fp_line
			(start 0.67945 0.3048)
			(end 0.120396 0.3048)
			(stroke
				(width 0.1)
				(type default)
			)
			(layer "F.Fab")
		)
		(pad "1" smd circle
			(at -0.40005 0)
			(size 0 0)
			(layers "F.Cu" "F.Mask" "F.Paste")
			(net "SMB_2_BMC_GPU_BUF_R_SCL")
		)
		(pad "2" smd circle
			(at 0.40005 0)
			(size 0 0)
			(layers "F.Cu" "F.Mask" "F.Paste")
			(net "SMB_2_BMC_GPU_BUF_SCL")
		)
	)
	(footprint ""
		(layer "F.Cu")
		(at 68.16852 -395.6304 -90)
		(property "Reference" "R6708"
			(at 0 0 270)
			(layer "F.SilkS")
			(hide yes)
			(effects
				(font
					(size 1.27 1.27)
				)
			)
		)
		(property "Value" ""
			(at 0 0 270)
			(layer "F.Fab")
			(effects
				(font
					(size 1.27 1.27)
				)
			)
		)
		(duplicate_pad_numbers_are_jumpers no)
		(fp_line
			(start -0.32512 0.175006)
			(end -0.32512 -0.175006)
			(stroke
				(width 0.1)
				(type default)
			)
			(layer "F.Fab")
		)
		(fp_line
			(start 0.32512 0.175006)
			(end -0.32512 0.175006)
			(stroke
				(width 0.1)
				(type default)
			)
			(layer "F.Fab")
		)
		(fp_line
			(start -0.32512 -0.175006)
			(end 0.32512 -0.175006)
			(stroke
				(width 0.1)
				(type default)
			)
			(layer "F.Fab")
		)
		(fp_line
			(start 0.32512 -0.175006)
			(end 0.32512 0.175006)
			(stroke
				(width 0.1)
				(type default)
			)
			(layer "F.Fab")
		)
		(pad "1" smd rect
			(at -0.2667 0 270)
			(size 0.3048 0.381)
			(layers "F.Cu" "F.Mask" "F.Paste")
			(net "RST_RT_CPU1_P0_PERST_N")
		)
		(pad "2" smd rect
			(at 0.2667 0 90)
			(size 0.3048 0.381)
			(layers "F.Cu" "F.Mask" "F.Paste")
			(net "RST_RT_CPU1_P0_PERST_R_N")
		)
	)
)
